# BASEBOARD_FAB2 (Tioga Pass) — schematic parts with pin connectivity, parts 2360–2362 of 4751; source: Cadence DE-HDL packaged netlist (pstxprt.dat, pstxnet.dat, pstchip.dat)

J1G3  SCONN288_H44441004  SCONN  pkg PIP  page 81
  1  \12v\(1)  = P12V_NVDIMM_GHJ
  2  VSS(93)  GROUND  = GND
  3  DQ(4)  BI  = M_J_DQ<5>
  4  VSS(92)  GROUND  = GND
  5  DQ(0)  BI  = M_J_DQ<1>
  6  VSS(91)  GROUND  = GND
  7  DQS9P  BI  = M_J_DQS_DP<9>
  8  DQS9N  BI  = M_J_DQS_DN<9>
  9  VSS(90)  GROUND  = GND
  10  DQ(6)  BI  = M_J_DQ<7>
  11  VSS(89)  GROUND  = GND
  12  DQ(2)  BI  = M_J_DQ<3>
  13  VSS(88)  GROUND  = GND
  14  DQ(12)  BI  = M_J_DQ<13>
  15  VSS(87)  GROUND  = GND
  16  DQ(8)  BI  = M_J_DQ<9>
  17  VSS(86)  GROUND  = GND
  18  DQS10P  BI  = M_J_DQS_DP<10>
  19  DQS10N  BI  = M_J_DQS_DN<10>
  20  VSS(85)  GROUND  = GND
  21  DQ(14)  BI  = M_J_DQ<15>
  22  VSS(84)  GROUND  = GND
  23  DQ(10)  BI  = M_J_DQ<11>
  24  VSS(83)  GROUND  = GND
  25  DQ(20)  BI  = M_J_DQ<21>
  26  VSS(82)  GROUND  = GND
  27  DQ(16)  BI  = M_J_DQ<17>
  28  VSS(81)  GROUND  = GND
  29  DQS11P  BI  = M_J_DQS_DP<11>
  30  DQS11N  BI  = M_J_DQS_DN<11>
  31  VSS(80)  GROUND  = GND
  32  DQ(22)  BI  = M_J_DQ<23>
  33  VSS(79)  GROUND  = GND
  34  DQ(18)  BI  = M_J_DQ<19>
  35  VSS(78)  GROUND  = GND
  36  DQ(28)  BI  = M_J_DQ<29>
  37  VSS(77)  GROUND  = GND
  38  DQ(24)  BI  = M_J_DQ<25>
  39  VSS(76)  GROUND  = GND
  40  DQS12P  BI  = M_J_DQS_DP<12>
  41  DQS12N  BI  = M_J_DQS_DN<12>
  42  VSS(75)  GROUND  = GND
  43  DQ(30)  BI  = M_J_DQ<31>
  44  VSS(74)  GROUND  = GND
  45  DQ(26)  BI  = M_J_DQ<27>
  46  VSS(73)  GROUND  = GND
  47  CB(4)  BI  = M_J_ECC<5>
  48  VSS(72)  GROUND  = GND
  49  CB(0)  BI  = M_J_ECC<1>
  50  VSS(71)  GROUND  = GND
  51  DQS17P  BI  = M_J_DQS_DP<17>
  52  DQS17N  BI  = M_J_DQS_DN<17>
  53  VSS(70)  GROUND  = GND
  54  CB(6)  BI  = M_J_ECC<7>
  55  VSS(69)  GROUND  = GND
  56  CB(2)  BI  = M_J_ECC<3>
  57  VSS(68)  GROUND  = GND
  58  RESET_N  BI  = M_GHJ_RST_N
  59  VDD(25)  POWER  = PVDDQ_GHJ
  60  CKE(0)  BI  = M_J_CKE<0>
  61  VDD(24)  POWER  = PVDDQ_GHJ
  62  ACT_N  BI  = M_J_ACT_N
  63  BG(0)  BI  = M_J_BG<0>
  64  VDD(23)  POWER  = PVDDQ_GHJ
  65  A12  BI  = M_J_MA<12>
  66  A9  BI  = M_J_MA<9>
  67  VDD(22)  POWER  = PVDDQ_GHJ
  68  A8  BI  = M_J_MA<8>
  69  A6  BI  = M_J_MA<6>
  70  VDD(21)  POWER  = PVDDQ_GHJ
  71  A3  BI  = M_J_MA<3>
  72  A1  BI  = M_J_MA<1>
  73  VDD(20)  POWER  = PVDDQ_GHJ
  74  CK0P  BI  = M_J_CLK_DP<0>
  75  CK0N  BI  = M_J_CLK_DN<0>
  76  VDD(19)  POWER  = PVDDQ_GHJ
  77  VTT(1)  POWER  = PVTT_GHJ
  78  EVENT_N  BI  = FM_DIMM_EVENT_COD_N
  79  A0  BI  = M_J_MA<0>
  80  VDD(18)  POWER  = PVDDQ_GHJ
  81  BA(0)  BI  = M_J_BA<0>
  82  A16_RAS_N  BI  = M_J_MA<16>
  83  VDD(17)  POWER  = PVDDQ_GHJ
  84  S0_N  BI  = M_J_CS_N<0>
  85  VDD(16)  POWER  = PVDDQ_GHJ
  86  A15_CAS_N  BI  = M_J_MA<15>
  87  ODT(0)  BI  = M_J_ODT<0>
  88  VDD(15)  POWER  = PVDDQ_GHJ
  89  S1_N  BI  = M_J_CS_N<1>
  90  VDD(14)  POWER  = PVDDQ_GHJ
  91  ODT(1)  BI  = M_J_ODT<1>
  92  VDD(13)  POWER  = PVDDQ_GHJ
  93  S2_N_C(0)  BI  = M_J_CS_N<2>
  94  VSS(67)  GROUND  = GND
  95  DQ(36)  BI  = M_J_DQ<37>
  96  VSS(66)  GROUND  = GND
  97  DQ(32)  BI  = M_J_DQ<33>
  98  VSS(65)  GROUND  = GND
  99  DQS13P  BI  = M_J_DQS_DP<13>
  100  DQS13N  BI  = M_J_DQS_DN<13>
  101  VSS(64)  GROUND  = GND
  102  DQ(38)  BI  = M_J_DQ<39>
  103  VSS(63)  GROUND  = GND
  104  DQ(34)  BI  = M_J_DQ<35>
  105  VSS(62)  GROUND  = GND
  106  DQ(44)  BI  = M_J_DQ<45>
  107  VSS(61)  GROUND  = GND
  108  DQ(40)  BI  = M_J_DQ<41>
  109  VSS(60)  GROUND  = GND
  110  DQS14P  BI  = M_J_DQS_DP<14>
  111  DQS14N  BI  = M_J_DQS_DN<14>
  112  VSS(59)  GROUND  = GND
  113  DQ(46)  BI  = M_J_DQ<47>
  114  VSS(58)  GROUND  = GND
  115  DQ(42)  BI  = M_J_DQ<43>
  116  VSS(57)  GROUND  = GND
  117  DQ(52)  BI  = M_J_DQ<53>
  118  VSS(56)  GROUND  = GND
  119  DQ(48)  BI  = M_J_DQ<49>
  120  VSS(55)  GROUND  = GND
  121  DQS15P  BI  = M_J_DQS_DP<15>
  122  DQS15N  BI  = M_J_DQS_DN<15>
  123  VSS(54)  GROUND  = GND
  124  DQ(54)  BI  = M_J_DQ<55>
  125  VSS(53)  GROUND  = GND
  126  DQ(50)  BI  = M_J_DQ<51>
  127  VSS(52)  GROUND  = GND
  128  DQ(60)  BI  = M_J_DQ<61>
  129  VSS(51)  GROUND  = GND
  130  DQ(56)  BI  = M_J_DQ<57>
  131  VSS(50)  GROUND  = GND
  132  DQS16P  BI  = M_J_DQS_DP<16>
  133  DQS16N  BI  = M_J_DQS_DN<16>
  134  VSS(49)  GROUND  = GND
  135  DQ(62)  BI  = M_J_DQ<63>
  136  VSS(48)  GROUND  = GND
  137  DQ(58)  BI  = M_J_DQ<59>
  138  VSS(47)  GROUND  = GND
  139  SA(0)  BI  = GND
  140  SA(1)  BI  = GND
  141  SCL  BI  = SMB_DDR_GHJ_VPP_SCL
  142  VPP(4)  POWER  = PVPP_GHJ
  143  VPP(3)  POWER  = PVPP_GHJ
  144  RFU(2)  BI  = TP_CH_J_DIMM_J0_RFU_2
  145  \12v\(0)  = P12V_NVDIMM_GHJ
  146  VREFCA  BI  = M_J_VREF
  147  VSS(46)  GROUND  = GND
  148  DQ(5)  BI  = M_J_DQ<4>
  149  VSS(45)  GROUND  = GND
  150  DQ(1)  BI  = M_J_DQ<0>
  151  VSS(44)  GROUND  = GND
  152  DQS0N  BI  = M_J_DQS_DN<0>
  153  DQS0P  BI  = M_J_DQS_DP<0>
  154  VSS(43)  GROUND  = GND
  155  DQ(7)  BI  = M_J_DQ<6>
  156  VSS(42)  GROUND  = GND
  157  DQ(3)  BI  = M_J_DQ<2>
  158  VSS(41)  GROUND  = GND
  159  DQ(13)  BI  = M_J_DQ<12>
  160  VSS(40)  GROUND  = GND
  161  DQ(9)  BI  = M_J_DQ<8>
  162  VSS(39)  GROUND  = GND
  163  DQS1N  BI  = M_J_DQS_DN<1>
  164  DQS1P  BI  = M_J_DQS_DP<1>
  165  VSS(38)  GROUND  = GND
  166  DQ(15)  BI  = M_J_DQ<14>
  167  VSS(37)  GROUND  = GND
  168  DQ(11)  BI  = M_J_DQ<10>
  169  VSS(36)  GROUND  = GND
  170  DQ(21)  BI  = M_J_DQ<20>
  171  VSS(35)  GROUND  = GND
  172  DQ(17)  BI  = M_J_DQ<16>
  173  VSS(34)  GROUND  = GND
  174  DQS2N  BI  = M_J_DQS_DN<2>
  175  DQS2P  BI  = M_J_DQS_DP<2>
  176  VSS(33)  GROUND  = GND
  177  DQ(23)  BI  = M_J_DQ<22>
  178  VSS(32)  GROUND  = GND
  179  DQ(19)  BI  = M_J_DQ<18>
  180  VSS(31)  GROUND  = GND
  181  DQ(29)  BI  = M_J_DQ<28>
  182  VSS(30)  GROUND  = GND
  183  DQ(25)  BI  = M_J_DQ<24>
  184  VSS(29)  GROUND  = GND
  185  DQS3N  BI  = M_J_DQS_DN<3>
  186  DQS3P  BI  = M_J_DQS_DP<3>
  187  VSS(28)  GROUND  = GND
  188  DQ(31)  BI  = M_J_DQ<30>
  189  VSS(27)  GROUND  = GND
  190  DQ(27)  BI  = M_J_DQ<26>
  191  VSS(26)  GROUND  = GND
  192  CB(5)  BI  = M_J_ECC<4>
  193  VSS(25)  GROUND  = GND
  194  CB(1)  BI  = M_J_ECC<0>
  195  VSS(24)  GROUND  = GND
  196  DQS8N  BI  = M_J_DQS_DN<8>
  197  DQS8P  BI  = M_J_DQS_DP<8>
  198  VSS(23)  GROUND  = GND
  199  CB(7)  BI  = M_J_ECC<6>
  200  VSS(22)  GROUND  = GND
  201  CB(3)  BI  = M_J_ECC<2>
  202  VSS(21)  GROUND  = GND
  203  CKE(1)  BI  = M_J_CKE<1>
  204  VDD(12)  POWER  = PVDDQ_GHJ
  205  RFU(0)  BI  = TP_CH_J_DIMM_J0_RFU_0
  206  VDD(11)  POWER  = PVDDQ_GHJ
  207  BG(1)  BI  = M_J_BG<1>
  208  ALERT_N  BI  = M_J_ALERT_N
  209  VDD(10)  POWER  = PVDDQ_GHJ
  210  A11  BI  = M_J_MA<11>
  211  A7  BI  = M_J_MA<7>
  212  VDD(9)  POWER  = PVDDQ_GHJ
  213  A5  BI  = M_J_MA<5>
  214  A4  BI  = M_J_MA<4>
  215  VDD(8)  POWER  = PVDDQ_GHJ
  216  A2  BI  = M_J_MA<2>
  217  VDD(7)  POWER  = PVDDQ_GHJ
  218  CK1P  BI  = M_J_CLK_DP<1>
  219  CK1N  BI  = M_J_CLK_DN<1>
  220  VDD(6)  POWER  = PVDDQ_GHJ
  221  VTT(0)  POWER  = PVTT_GHJ
  222  PAR  BI  = M_J_PAR
  223  VDD(5)  POWER  = PVDDQ_GHJ
  224  BA(1)  BI  = M_J_BA<1>
  225  A10  BI  = M_J_MA<10>
  226  VDD(4)  POWER  = PVDDQ_GHJ
  227  RFU(1)  BI  = TP_CH_J_DIMM_J0_RFU_1
  228  A14_WE_N  BI  = M_J_MA<14>
  229  VDD(3)  POWER  = PVDDQ_GHJ
  230  SAVE_N_NC  BI  = FM_ADR_COMPLETE_GHJ_N
  231  VDD(2)  POWER  = PVDDQ_GHJ
  232  A13  BI  = M_J_MA<13>
  233  VDD(1)  POWER  = PVDDQ_GHJ
  234  A17  BI  = M_J_MA<17>
  235  C(2)  BI  = M_J_C<2>
  236  VDD(0)  POWER  = PVDDQ_GHJ
  237  S3_N_C(1)  BI  = M_J_CS_N<3>
  238  SA(2)  BI  = PVPP_GHJ
  239  VSS(20)  GROUND  = GND
  240  DQ(37)  BI  = M_J_DQ<36>
  241  VSS(19)  GROUND  = GND
  242  DQ(33)  BI  = M_J_DQ<32>
  243  VSS(18)  GROUND  = GND
  244  DQS4N  BI  = M_J_DQS_DN<4>
  245  DQS4P  BI  = M_J_DQS_DP<4>
  246  VSS(17)  GROUND  = GND
  247  DQ(39)  BI  = M_J_DQ<38>
  248  VSS(16)  GROUND  = GND
  249  DQ(35)  BI  = M_J_DQ<34>
  250  VSS(15)  GROUND  = GND
  251  DQ(45)  BI  = M_J_DQ<44>
  252  VSS(14)  GROUND  = GND
  253  DQ(41)  BI  = M_J_DQ<40>
  254  VSS(13)  GROUND  = GND
  255  DQS5N  BI  = M_J_DQS_DN<5>
  256  DQS5P  BI  = M_J_DQS_DP<5>
  257  VSS(12)  GROUND  = GND
  258  DQ(47)  BI  = M_J_DQ<46>
  259  VSS(11)  GROUND  = GND
  260  DQ(43)  BI  = M_J_DQ<42>
  261  VSS(10)  GROUND  = GND
  262  DQ(53)  BI  = M_J_DQ<52>
  263  VSS(9)  GROUND  = GND
  264  DQ(49)  BI  = M_J_DQ<48>
  265  VSS(8)  GROUND  = GND
  266  DQS6N  BI  = M_J_DQS_DN<6>
  267  DQS6P  BI  = M_J_DQS_DP<6>
  268  VSS(7)  GROUND  = GND
  269  DQ(55)  BI  = M_J_DQ<54>
  270  VSS(6)  GROUND  = GND
  271  DQ(51)  BI  = M_J_DQ<50>
  272  VSS(5)  GROUND  = GND
  273  DQ(61)  BI  = M_J_DQ<60>
  274  VSS(4)  GROUND  = GND
  275  DQ(57)  BI  = M_J_DQ<56>
  276  VSS(3)  GROUND  = GND
  277  DQS7N  BI  = M_J_DQS_DN<7>
  278  DQS7P  BI  = M_J_DQS_DP<7>
  279  VSS(2)  GROUND  = GND
  280  DQ(63)  BI  = M_J_DQ<62>
  281  VSS(1)  GROUND  = GND
  282  DQ(59)  BI  = M_J_DQ<58>
  283  VSS(0)  GROUND  = GND
  284  VDDSPD  BI  = PVPP_GHJ
  285  SDA  BI  = SMB_DDR_GHJ_VPP_SDA
  286  VPP(1)  POWER  = PVPP_GHJ
  287  VPP(0)  POWER  = PVPP_GHJ
  288  VPP(2)  POWER  = PVPP_GHJ

J2W1  SKT-SATA7P-6P-165-GP-U1  pkg SOCKET-G6  page 172
  H1  H1  UNSPEC  = GND
  H2  H2  UNSPEC  = GND
  NP1  NP1  UNSPEC  = NC
  NP2  NP2  UNSPEC  = NC
  P1  P1  UNSPEC  = P5V_HDD_SATA
  P2  P2  UNSPEC  = P5V_HDD_SATA
  P3  P3  UNSPEC  = GND
  P4  P4  UNSPEC  = GND
  P5  P5  UNSPEC  = P12V_HDD_SATA
  P6  P6  UNSPEC  = P12V_HDD_SATA
  S1  S1  UNSPEC  = GND
  S2  S2  UNSPEC  = SATA6G_S1_TX_C_DP
  S3  S3  UNSPEC  = SATA6G_S1_TX_C_DN
  S4  S4  UNSPEC  = GND
  S5  S5  UNSPEC  = SATA6G_S1_RX_C_DN
  S6  S6  UNSPEC  = SATA6G_S1_RX_C_DP
  S7  S7  UNSPEC  = GND

J2W2  SKT-SATA7P-6P-165-GP-U1  pkg SOCKET-G6  page 172
  H1  H1  UNSPEC  = GND
  H2  H2  UNSPEC  = GND
  NP1  NP1  UNSPEC  = NC
  NP2  NP2  UNSPEC  = NC
  P1  P1  UNSPEC  = P5V_HDD_SATA
  P2  P2  UNSPEC  = P5V_HDD_SATA
  P3  P3  UNSPEC  = GND
  P4  P4  UNSPEC  = GND
  P5  P5  UNSPEC  = P12V_HDD_SATA
  P6  P6  UNSPEC  = P12V_HDD_SATA
  S1  S1  UNSPEC  = GND
  S2  S2  UNSPEC  = SATA6G_S1_TX_C_DP
  S3  S3  UNSPEC  = SATA6G_S1_TX_C_DN
  S4  S4  UNSPEC  = GND
  S5  S5  UNSPEC  = SATA6G_S1_RX_C_DN
  S6  S6  UNSPEC  = SATA6G_S1_RX_C_DP
  S7  S7  UNSPEC  = GND
